# T6G (Grand Teton) — schematic netlist excerpt (pin names and nets, part order shuffled) for the footprints in the layout excerpt that follows; sources: Cadence DE-HDL packaged netlist, KiCad conversion of 04192023_DAF0TMB3IC0_F0TG_MB_C_brd_V02_OCP.brd

R341  Q_RES  51 5% EMPTY  pkg 0402LF  page 180 : A = USB3_CPU0_BMC_TX_DP ; B = GND
R2627  Q_RES  0 5% CHIP  pkg 0402LF  page 267 : A = SMB_P12V_HSC_TEMP_SDA ; B = SMB_P12V_HSC_SDA
C860  Q_CAP_DIFFBUS  DIFF BUS_0.22UF 6.3V 20% X6S  pkg C0201  page 64 : \1\ = P5E_CPU0_P2_TX_C_DN<4> ; \2\ = P5E_CPU0_P2_TX_DN<4>

(kicad_pcb
	(version 20260206)
	(generator "pcbnew")
	(generator_version "10.0")
	(general
		(thickness 1.6)
		(legacy_teardrops no)
	)
	(paper "A4")
	(title_block
		(title "04192023_DAF0TMB3IC0_F0TG_MB_C_brd_V02_OCP.brd")
		(comment 1 "Grand Teton / footprints 4180-4182 of 8354")
	)
	(layers
		(0 "F.Cu" signal "TOP")
		(4 "In1.Cu" signal "GND")
		(6 "In2.Cu" signal "IN1")
		(8 "In3.Cu" signal "GND1")
		(10 "In4.Cu" signal "IN2")
		(12 "In5.Cu" signal "GND2")
		(14 "In6.Cu" signal "IN3")
		(16 "In7.Cu" signal "GND3")
		(18 "In8.Cu" signal "VCC")
		(20 "In9.Cu" signal "VCC1")
		(22 "In10.Cu" signal "GND4")
		(24 "In11.Cu" signal "IN4")
		(26 "In12.Cu" signal "GND5")
		(28 "In13.Cu" signal "IN5")
		(30 "In14.Cu" signal "GND6")
		(32 "In15.Cu" signal "IN6")
		(34 "In16.Cu" signal "GND7")
		(2 "B.Cu" signal "BOTTOM")
		(9 "F.Adhes" user "F.Adhesive")
		(11 "B.Adhes" user "B.Adhesive")
		(13 "F.Paste" user "Package Geometry/Pastemask Top")
		(15 "B.Paste" user "Package Geometry/Pastemask Bottom")
		(5 "F.SilkS" user "Ref Des/Silkscreen Top")
		(7 "B.SilkS" user "Ref Des/Silkscreen Bottom")
		(1 "F.Mask" user "Board Geometry/Soldermask Top")
		(3 "B.Mask" user "Board Geometry/Soldermask Bottom")
		(17 "Dwgs.User" user "User.Drawings")
		(19 "Cmts.User" user "User.Comments")
		(21 "Eco1.User" user "User.Eco1")
		(23 "Eco2.User" user "User.Eco2")
		(25 "Edge.Cuts" user "Board Geometry/Outline")
		(27 "Margin" user)
		(31 "F.CrtYd" user "Package Geometry/Place Bound Top")
		(29 "B.CrtYd" user "Package Geometry/Place Bound Bottom")
		(35 "F.Fab" user "Ref Des/Assembly Top")
		(33 "B.Fab" user "Ref Des/Assembly Bottom")
	)
	(footprint ""
		(layer "F.Cu")
		(at 146.03349 -31.18739)
		(property "Reference" "R341"
			(at 0 0 0)
			(layer "F.SilkS")
			(hide yes)
			(effects
				(font
					(size 1.27 1.27)
				)
			)
		)
		(property "Value" ""
			(at 0 0 0)
			(layer "F.Fab")
			(effects
				(font
					(size 1.27 1.27)
				)
			)
		)
		(duplicate_pad_numbers_are_jumpers no)
		(fp_line
			(start -0.7874 -0.4064)
			(end 0.7874 -0.4064)
			(stroke
				(width 0.1524)
				(type default)
			)
			(layer "F.SilkS")
		)
		(fp_line
			(start -0.7874 0.4064)
			(end -0.7874 -0.4064)
			(stroke
				(width 0.1524)
				(type default)
			)
			(layer "F.SilkS")
		)
		(fp_line
			(start 0.7874 -0.4064)
			(end 0.7874 0.4064)
			(stroke
				(width 0.1524)
				(type default)
			)
			(layer "F.SilkS")
		)
		(fp_line
			(start 0.7874 0.4064)
			(end -0.7874 0.4064)
			(stroke
				(width 0.1524)
				(type default)
			)
			(layer "F.SilkS")
		)
		(fp_line
			(start -0.67945 -0.305054)
			(end -0.12065 -0.305054)
			(stroke
				(width 0.1)
				(type default)
			)
			(layer "F.Fab")
		)
		(fp_line
			(start -0.67945 0.3048)
			(end -0.67945 -0.305054)
			(stroke
				(width 0.1)
				(type default)
			)
			(layer "F.Fab")
		)
		(fp_line
			(start -0.12065 -0.305054)
			(end -0.12065 -0.2794)
			(stroke
				(width 0.1)
				(type default)
			)
			(layer "F.Fab")
		)
		(fp_line
			(start -0.12065 -0.2794)
			(end 0.12065 -0.2794)
			(stroke
				(width 0.1)
				(type default)
			)
			(layer "F.Fab")
		)
		(fp_line
			(start -0.12065 0.2794)
			(end -0.12065 0.3048)
			(stroke
				(width 0.1)
				(type default)
			)
			(layer "F.Fab")
		)
		(fp_line
			(start -0.12065 0.3048)
			(end -0.67945 0.3048)
			(stroke
				(width 0.1)
				(type default)
			)
			(layer "F.Fab")
		)
		(fp_line
			(start 0.120396 0.2794)
			(end -0.12065 0.2794)
			(stroke
				(width 0.1)
				(type default)
			)
			(layer "F.Fab")
		)
		(fp_line
			(start 0.120396 0.3048)
			(end 0.120396 0.2794)
			(stroke
				(width 0.1)
				(type default)
			)
			(layer "F.Fab")
		)
		(fp_line
			(start 0.12065 -0.3048)
			(end 0.67945 -0.3048)
			(stroke
				(width 0.1)
				(type default)
			)
			(layer "F.Fab")
		)
		(fp_line
			(start 0.12065 -0.2794)
			(end 0.12065 -0.3048)
			(stroke
				(width 0.1)
				(type default)
			)
			(layer "F.Fab")
		)
		(fp_line
			(start 0.67945 -0.3048)
			(end 0.67945 0.3048)
			(stroke
				(width 0.1)
				(type default)
			)
			(layer "F.Fab")
		)
		(fp_line
			(start 0.67945 0.3048)
			(end 0.120396 0.3048)
			(stroke
				(width 0.1)
				(type default)
			)
			(layer "F.Fab")
		)
		(pad "1" smd rect
			(at -0.40005 0 180)
			(size 0.4572 0.508)
			(layers "F.Cu" "F.Mask" "F.Paste")
			(net "USB3_CPU0_BMC_TX_DP")
		)
		(pad "2" smd rect
			(at 0.40005 0 180)
			(size 0.4572 0.508)
			(layers "F.Cu" "F.Mask" "F.Paste")
			(net "GND")
		)
	)
	(footprint ""
		(layer "F.Cu")
		(at 281.621738 -390.49452 -90)
		(property "Reference" "R2627"
			(at 0 0 270)
			(layer "F.SilkS")
			(hide yes)
			(effects
				(font
					(size 1.27 1.27)
				)
			)
		)
		(property "Value" ""
			(at 0 0 270)
			(layer "F.Fab")
			(effects
				(font
					(size 1.27 1.27)
				)
			)
		)
		(duplicate_pad_numbers_are_jumpers no)
		(fp_line
			(start -0.7874 0.4064)
			(end -0.7874 -0.4064)
			(stroke
				(width 0.1524)
				(type default)
			)
			(layer "F.SilkS")
		)
		(fp_line
			(start 0.7874 0.4064)
			(end -0.7874 0.4064)
			(stroke
				(width 0.1524)
				(type default)
			)
			(layer "F.SilkS")
		)
		(fp_line
			(start -0.7874 -0.4064)
			(end 0.7874 -0.4064)
			(stroke
				(width 0.1524)
				(type default)
			)
			(layer "F.SilkS")
		)
		(fp_line
			(start 0.7874 -0.4064)
			(end 0.7874 0.4064)
			(stroke
				(width 0.1524)
				(type default)
			)
			(layer "F.SilkS")
		)
		(fp_line
			(start -0.67945 0.3048)
			(end -0.67945 -0.305054)
			(stroke
				(width 0.1)
				(type default)
			)
			(layer "F.Fab")
		)
		(fp_line
			(start -0.12065 0.3048)
			(end -0.67945 0.3048)
			(stroke
				(width 0.1)
				(type default)
			)
			(layer "F.Fab")
		)
		(fp_line
			(start 0.120396 0.3048)
			(end 0.120396 0.2794)
			(stroke
				(width 0.1)
				(type default)
			)
			(layer "F.Fab")
		)
		(fp_line
			(start 0.67945 0.3048)
			(end 0.120396 0.3048)
			(stroke
				(width 0.1)
				(type default)
			)
			(layer "F.Fab")
		)
		(fp_line
			(start -0.12065 0.2794)
			(end -0.12065 0.3048)
			(stroke
				(width 0.1)
				(type default)
			)
			(layer "F.Fab")
		)
		(fp_line
			(start 0.120396 0.2794)
			(end -0.12065 0.2794)
			(stroke
				(width 0.1)
				(type default)
			)
			(layer "F.Fab")
		)
		(fp_line
			(start -0.12065 -0.2794)
			(end 0.12065 -0.2794)
			(stroke
				(width 0.1)
				(type default)
			)
			(layer "F.Fab")
		)
		(fp_line
			(start 0.12065 -0.2794)
			(end 0.12065 -0.3048)
			(stroke
				(width 0.1)
				(type default)
			)
			(layer "F.Fab")
		)
		(fp_line
			(start 0.12065 -0.3048)
			(end 0.67945 -0.3048)
			(stroke
				(width 0.1)
				(type default)
			)
			(layer "F.Fab")
		)
		(fp_line
			(start 0.67945 -0.3048)
			(end 0.67945 0.3048)
			(stroke
				(width 0.1)
				(type default)
			)
			(layer "F.Fab")
		)
		(fp_line
			(start -0.67945 -0.305054)
			(end -0.12065 -0.305054)
			(stroke
				(width 0.1)
				(type default)
			)
			(layer "F.Fab")
		)
		(fp_line
			(start -0.12065 -0.305054)
			(end -0.12065 -0.2794)
			(stroke
				(width 0.1)
				(type default)
			)
			(layer "F.Fab")
		)
		(pad "1" smd circle
			(at -0.40005 0 270)
			(size 0 0)
			(layers "F.Cu" "F.Mask" "F.Paste")
			(net "SMB_P12V_HSC_TEMP_SDA")
		)
		(pad "2" smd circle
			(at 0.40005 0 270)
			(size 0 0)
			(layers "F.Cu" "F.Mask" "F.Paste")
			(net "SMB_P12V_HSC_SDA")
		)
	)
	(footprint ""
		(layer "F.Cu")
		(at 404.63724 -383.88163 -90)
		(property "Reference" "C860"
			(at 0 0 270)
			(layer "F.SilkS")
			(hide yes)
			(effects
				(font
					(size 1.27 1.27)
				)
			)
		)
		(property "Value" ""
			(at 0 0 270)
			(layer "F.Fab")
			(effects
				(font
					(size 1.27 1.27)
				)
			)
		)
		(duplicate_pad_numbers_are_jumpers no)
		(fp_line
			(start -0.299974 0.150114)
			(end -0.299974 -0.150114)
			(stroke
				(width 0.1)
				(type default)
			)
			(layer "F.Fab")
		)
		(fp_line
			(start 0.299974 0.150114)
			(end -0.299974 0.150114)
			(stroke
				(width 0.1)
				(type default)
			)
			(layer "F.Fab")
		)
		(fp_line
			(start -0.299974 -0.150114)
			(end 0.299974 -0.150114)
			(stroke
				(width 0.1)
				(type default)
			)
			(layer "F.Fab")
		)
		(fp_line
			(start 0.299974 -0.150114)
			(end 0.299974 0.150114)
			(stroke
				(width 0.1)
				(type default)
			)
			(layer "F.Fab")
		)
		(pad "1" smd rect
			(at -0.2667 0 270)
			(size 0.3048 0.381)
			(layers "F.Cu" "F.Mask" "F.Paste")
			(net "P5E_CPU0_P2_TX_C_DN<4>")
		)
		(pad "2" smd rect
			(at 0.2667 0 270)
			(size 0.3048 0.381)
			(layers "F.Cu" "F.Mask" "F.Paste")
			(net "P5E_CPU0_P2_TX_DN<4>")
		)
	)
)
